(kicad_pcb
	(version 20260206)
	(generator "pcbnew")
	(generator_version "10.0")
	(general
		(thickness 1.6)
		(legacy_teardrops no)
	)
	(paper "A4")
	(title_block
		(title "03242023_DA0F0TMBIJ0_F0T_Motherboard_J_brd_V01_OCP.brd")
		(comment 1 "Grand Teton / footprints 3394-3399 of 6105")
	)
	(layers
		(0 "F.Cu" signal "TOP")
		(4 "In1.Cu" signal "GND")
		(6 "In2.Cu" signal "IN1")
		(8 "In3.Cu" signal "GND1")
		(10 "In4.Cu" signal "IN2")
		(12 "In5.Cu" signal "GND2")
		(14 "In6.Cu" signal "IN3")
		(16 "In7.Cu" signal "GND3")
		(18 "In8.Cu" signal "VCC")
		(20 "In9.Cu" signal "VCC1")
		(22 "In10.Cu" signal "GND4")
		(24 "In11.Cu" signal "IN4")
		(26 "In12.Cu" signal "GND5")
		(28 "In13.Cu" signal "IN5")
		(30 "In14.Cu" signal "GND6")
		(32 "In15.Cu" signal "IN6")
		(34 "In16.Cu" signal "GND7")
		(2 "B.Cu" signal "BOTTOM")
		(9 "F.Adhes" user "F.Adhesive")
		(11 "B.Adhes" user "B.Adhesive")
		(13 "F.Paste" user "Package Geometry/Pastemask Top")
		(15 "B.Paste" user "Package Geometry/Pastemask Bottom")
		(5 "F.SilkS" user "Ref Des/Silkscreen Top")
		(7 "B.SilkS" user "Ref Des/Silkscreen Bottom")
		(1 "F.Mask" user "Board Geometry/Soldermask Top")
		(3 "B.Mask" user "Board Geometry/Soldermask Bottom")
		(17 "Dwgs.User" user "User.Drawings")
		(19 "Cmts.User" user "User.Comments")
		(21 "Eco1.User" user "User.Eco1")
		(23 "Eco2.User" user "User.Eco2")
		(25 "Edge.Cuts" user "Board Geometry/Outline")
		(27 "Margin" user)
		(31 "F.CrtYd" user "Package Geometry/Place Bound Top")
		(29 "B.CrtYd" user "Package Geometry/Place Bound Bottom")
		(35 "F.Fab" user "Ref Des/Assembly Top")
		(33 "B.Fab" user "Ref Des/Assembly Bottom")
	)
	(footprint ""
		(layer "F.Cu")
		(at 38.02888 -433.923948)
		(property "Reference" "R3109"
			(at 0 0 0)
			(layer "F.SilkS")
			(hide yes)
			(effects
				(font
					(size 1.27 1.27)
				)
			)
		)
		(property "Value" ""
			(at 0 0 0)
			(layer "F.Fab")
			(effects
				(font
					(size 1.27 1.27)
				)
			)
		)
		(duplicate_pad_numbers_are_jumpers no)
		(fp_line
			(start -0.7874 -0.4064)
			(end 0.7874 -0.4064)
			(stroke
				(width 0.1524)
				(type default)
			)
			(layer "F.SilkS")
		)
		(fp_line
			(start -0.7874 0.4064)
			(end -0.7874 -0.4064)
			(stroke
				(width 0.1524)
				(type default)
			)
			(layer "F.SilkS")
		)
		(fp_line
			(start 0.7874 -0.4064)
			(end 0.7874 0.4064)
			(stroke
				(width 0.1524)
				(type default)
			)
			(layer "F.SilkS")
		)
		(fp_line
			(start 0.7874 0.4064)
			(end -0.7874 0.4064)
			(stroke
				(width 0.1524)
				(type default)
			)
			(layer "F.SilkS")
		)
		(fp_line
			(start -0.67945 -0.305054)
			(end -0.12065 -0.305054)
			(stroke
				(width 0.1)
				(type default)
			)
			(layer "F.Fab")
		)
		(fp_line
			(start -0.67945 0.3048)
			(end -0.67945 -0.305054)
			(stroke
				(width 0.1)
				(type default)
			)
			(layer "F.Fab")
		)
		(fp_line
			(start -0.12065 -0.305054)
			(end -0.12065 -0.2794)
			(stroke
				(width 0.1)
				(type default)
			)
			(layer "F.Fab")
		)
		(fp_line
			(start -0.12065 -0.2794)
			(end 0.12065 -0.2794)
			(stroke
				(width 0.1)
				(type default)
			)
			(layer "F.Fab")
		)
		(fp_line
			(start -0.12065 0.2794)
			(end -0.12065 0.3048)
			(stroke
				(width 0.1)
				(type default)
			)
			(layer "F.Fab")
		)
		(fp_line
			(start -0.12065 0.3048)
			(end -0.67945 0.3048)
			(stroke
				(width 0.1)
				(type default)
			)
			(layer "F.Fab")
		)
		(fp_line
			(start 0.120396 0.2794)
			(end -0.12065 0.2794)
			(stroke
				(width 0.1)
				(type default)
			)
			(layer "F.Fab")
		)
		(fp_line
			(start 0.120396 0.3048)
			(end 0.120396 0.2794)
			(stroke
				(width 0.1)
				(type default)
			)
			(layer "F.Fab")
		)
		(fp_line
			(start 0.12065 -0.3048)
			(end 0.67945 -0.3048)
			(stroke
				(width 0.1)
				(type default)
			)
			(layer "F.Fab")
		)
		(fp_line
			(start 0.12065 -0.2794)
			(end 0.12065 -0.3048)
			(stroke
				(width 0.1)
				(type default)
			)
			(layer "F.Fab")
		)
		(fp_line
			(start 0.67945 -0.3048)
			(end 0.67945 0.3048)
			(stroke
				(width 0.1)
				(type default)
			)
			(layer "F.Fab")
		)
		(fp_line
			(start 0.67945 0.3048)
			(end 0.120396 0.3048)
			(stroke
				(width 0.1)
				(type default)
			)
			(layer "F.Fab")
		)
		(pad "1" smd circle
			(at -0.40005 0)
			(size 0 0)
			(layers "F.Cu" "F.Mask" "F.Paste")
			(net "SMB_1_BMC_GPU_SCL")
		)
		(pad "2" smd circle
			(at 0.40005 0)
			(size 0 0)
			(layers "F.Cu" "F.Mask" "F.Paste")
			(net "SMB_1_BMC_GPU_R_SCL")
		)
	)
	(footprint ""
		(layer "F.Cu")
		(at 124.672344 -78.587092 180)
		(property "Reference" "R1814"
			(at 0 0 180)
			(layer "F.SilkS")
			(hide yes)
			(effects
				(font
					(size 1.27 1.27)
				)
			)
		)
		(property "Value" ""
			(at 0 0 180)
			(layer "F.Fab")
			(effects
				(font
					(size 1.27 1.27)
				)
			)
		)
		(duplicate_pad_numbers_are_jumpers no)
		(fp_line
			(start 0.7874 0.4064)
			(end -0.7874 0.4064)
			(stroke
				(width 0.1524)
				(type default)
			)
			(layer "F.SilkS")
		)
		(fp_line
			(start 0.7874 -0.4064)
			(end 0.7874 0.4064)
			(stroke
				(width 0.1524)
				(type default)
			)
			(layer "F.SilkS")
		)
		(fp_line
			(start -0.7874 0.4064)
			(end -0.7874 -0.4064)
			(stroke
				(width 0.1524)
				(type default)
			)
			(layer "F.SilkS")
		)
		(fp_line
			(start -0.7874 -0.4064)
			(end 0.7874 -0.4064)
			(stroke
				(width 0.1524)
				(type default)
			)
			(layer "F.SilkS")
		)
		(fp_line
			(start 0.67945 0.3048)
			(end 0.120396 0.3048)
			(stroke
				(width 0.1)
				(type default)
			)
			(layer "F.Fab")
		)
		(fp_line
			(start 0.67945 -0.3048)
			(end 0.67945 0.3048)
			(stroke
				(width 0.1)
				(type default)
			)
			(layer "F.Fab")
		)
		(fp_line
			(start 0.12065 -0.2794)
			(end 0.12065 -0.3048)
			(stroke
				(width 0.1)
				(type default)
			)
			(layer "F.Fab")
		)
		(fp_line
			(start 0.12065 -0.3048)
			(end 0.67945 -0.3048)
			(stroke
				(width 0.1)
				(type default)
			)
			(layer "F.Fab")
		)
		(fp_line
			(start 0.120396 0.3048)
			(end 0.120396 0.2794)
			(stroke
				(width 0.1)
				(type default)
			)
			(layer "F.Fab")
		)
		(fp_line
			(start 0.120396 0.2794)
			(end -0.12065 0.2794)
			(stroke
				(width 0.1)
				(type default)
			)
			(layer "F.Fab")
		)
		(fp_line
			(start -0.12065 0.3048)
			(end -0.67945 0.3048)
			(stroke
				(width 0.1)
				(type default)
			)
			(layer "F.Fab")
		)
		(fp_line
			(start -0.12065 0.2794)
			(end -0.12065 0.3048)
			(stroke
				(width 0.1)
				(type default)
			)
			(layer "F.Fab")
		)
		(fp_line
			(start -0.12065 -0.2794)
			(end 0.12065 -0.2794)
			(stroke
				(width 0.1)
				(type default)
			)
			(layer "F.Fab")
		)
		(fp_line
			(start -0.12065 -0.305054)
			(end -0.12065 -0.2794)
			(stroke
				(width 0.1)
				(type default)
			)
			(layer "F.Fab")
		)
		(fp_line
			(start -0.67945 0.3048)
			(end -0.67945 -0.305054)
			(stroke
				(width 0.1)
				(type default)
			)
			(layer "F.Fab")
		)
		(fp_line
			(start -0.67945 -0.305054)
			(end -0.12065 -0.305054)
			(stroke
				(width 0.1)
				(type default)
			)
			(layer "F.Fab")
		)
		(pad "1" smd circle
			(at -0.40005 0 180)
			(size 0 0)
			(layers "F.Cu" "F.Mask" "F.Paste")
			(net "FM_JTAG_BMC_MUX_SEL")
		)
		(pad "2" smd circle
			(at 0.40005 0 180)
			(size 0 0)
			(layers "F.Cu" "F.Mask" "F.Paste")
			(net "GND")
		)
	)
	(footprint ""
		(layer "F.Cu")
		(at 272.07337 -98.227642 180)
		(property "Reference" "R111"
			(at 0 0 180)
			(layer "F.SilkS")
			(hide yes)
			(effects
				(font
					(size 1.27 1.27)
				)
			)
		)
		(property "Value" ""
			(at 0 0 180)
			(layer "F.Fab")
			(effects
				(font
					(size 1.27 1.27)
				)
			)
		)
		(duplicate_pad_numbers_are_jumpers no)
		(fp_line
			(start 0.7874 0.4064)
			(end -0.7874 0.4064)
			(stroke
				(width 0.1524)
				(type default)
			)
			(layer "F.SilkS")
		)
		(fp_line
			(start 0.7874 -0.4064)
			(end 0.7874 0.4064)
			(stroke
				(width 0.1524)
				(type default)
			)
			(layer "F.SilkS")
		)
		(fp_line
			(start -0.7874 0.4064)
			(end -0.7874 -0.4064)
			(stroke
				(width 0.1524)
				(type default)
			)
			(layer "F.SilkS")
		)
		(fp_line
			(start -0.7874 -0.4064)
			(end 0.7874 -0.4064)
			(stroke
				(width 0.1524)
				(type default)
			)
			(layer "F.SilkS")
		)
		(fp_line
			(start 0.67945 0.3048)
			(end 0.120396 0.3048)
			(stroke
				(width 0.1)
				(type default)
			)
			(layer "F.Fab")
		)
		(fp_line
			(start 0.67945 -0.3048)
			(end 0.67945 0.3048)
			(stroke
				(width 0.1)
				(type default)
			)
			(layer "F.Fab")
		)
		(fp_line
			(start 0.12065 -0.2794)
			(end 0.12065 -0.3048)
			(stroke
				(width 0.1)
				(type default)
			)
			(layer "F.Fab")
		)
		(fp_line
			(start 0.12065 -0.3048)
			(end 0.67945 -0.3048)
			(stroke
				(width 0.1)
				(type default)
			)
			(layer "F.Fab")
		)
		(fp_line
			(start 0.120396 0.3048)
			(end 0.120396 0.2794)
			(stroke
				(width 0.1)
				(type default)
			)
			(layer "F.Fab")
		)
		(fp_line
			(start 0.120396 0.2794)
			(end -0.12065 0.2794)
			(stroke
				(width 0.1)
				(type default)
			)
			(layer "F.Fab")
		)
		(fp_line
			(start -0.12065 0.3048)
			(end -0.67945 0.3048)
			(stroke
				(width 0.1)
				(type default)
			)
			(layer "F.Fab")
		)
		(fp_line
			(start -0.12065 0.2794)
			(end -0.12065 0.3048)
			(stroke
				(width 0.1)
				(type default)
			)
			(layer "F.Fab")
		)
		(fp_line
			(start -0.12065 -0.2794)
			(end 0.12065 -0.2794)
			(stroke
				(width 0.1)
				(type default)
			)
			(layer "F.Fab")
		)
		(fp_line
			(start -0.12065 -0.305054)
			(end -0.12065 -0.2794)
			(stroke
				(width 0.1)
				(type default)
			)
			(layer "F.Fab")
		)
		(fp_line
			(start -0.67945 0.3048)
			(end -0.67945 -0.305054)
			(stroke
				(width 0.1)
				(type default)
			)
			(layer "F.Fab")
		)
		(fp_line
			(start -0.67945 -0.305054)
			(end -0.12065 -0.305054)
			(stroke
				(width 0.1)
				(type default)
			)
			(layer "F.Fab")
		)
		(pad "1" smd circle
			(at -0.40005 0 180)
			(size 0 0)
			(layers "F.Cu" "F.Mask" "F.Paste")
			(net "P3V3")
		)
		(pad "2" smd circle
			(at 0.40005 0 180)
			(size 0 0)
			(layers "F.Cu" "F.Mask" "F.Paste")
			(net "FM_PLD_CLKS_OE_R_N")
		)
	)
	(footprint ""
		(layer "F.Cu")
		(at 22.225 -397.025876 -90)
		(property "Reference" "R3277"
			(at 0 0 270)
			(layer "F.SilkS")
			(hide yes)
			(effects
				(font
					(size 1.27 1.27)
				)
			)
		)
		(property "Value" ""
			(at 0 0 270)
			(layer "F.Fab")
			(effects
				(font
					(size 1.27 1.27)
				)
			)
		)
		(duplicate_pad_numbers_are_jumpers no)
		(fp_line
			(start -0.7874 0.4064)
			(end -0.7874 -0.4064)
			(stroke
				(width 0.1524)
				(type default)
			)
			(layer "F.SilkS")
		)
		(fp_line
			(start 0.7874 0.4064)
			(end -0.7874 0.4064)
			(stroke
				(width 0.1524)
				(type default)
			)
			(layer "F.SilkS")
		)
		(fp_line
			(start -0.7874 -0.4064)
			(end 0.7874 -0.4064)
			(stroke
				(width 0.1524)
				(type default)
			)
			(layer "F.SilkS")
		)
		(fp_line
			(start 0.7874 -0.4064)
			(end 0.7874 0.4064)
			(stroke
				(width 0.1524)
				(type default)
			)
			(layer "F.SilkS")
		)
		(fp_line
			(start -0.67945 0.3048)
			(end -0.67945 -0.305054)
			(stroke
				(width 0.1)
				(type default)
			)
			(layer "F.Fab")
		)
		(fp_line
			(start -0.12065 0.3048)
			(end -0.67945 0.3048)
			(stroke
				(width 0.1)
				(type default)
			)
			(layer "F.Fab")
		)
		(fp_line
			(start 0.120396 0.3048)
			(end 0.120396 0.2794)
			(stroke
				(width 0.1)
				(type default)
			)
			(layer "F.Fab")
		)
		(fp_line
			(start 0.67945 0.3048)
			(end 0.120396 0.3048)
			(stroke
				(width 0.1)
				(type default)
			)
			(layer "F.Fab")
		)
		(fp_line
			(start -0.12065 0.2794)
			(end -0.12065 0.3048)
			(stroke
				(width 0.1)
				(type default)
			)
			(layer "F.Fab")
		)
		(fp_line
			(start 0.120396 0.2794)
			(end -0.12065 0.2794)
			(stroke
				(width 0.1)
				(type default)
			)
			(layer "F.Fab")
		)
		(fp_line
			(start -0.12065 -0.2794)
			(end 0.12065 -0.2794)
			(stroke
				(width 0.1)
				(type default)
			)
			(layer "F.Fab")
		)
		(fp_line
			(start 0.12065 -0.2794)
			(end 0.12065 -0.3048)
			(stroke
				(width 0.1)
				(type default)
			)
			(layer "F.Fab")
		)
		(fp_line
			(start 0.12065 -0.3048)
			(end 0.67945 -0.3048)
			(stroke
				(width 0.1)
				(type default)
			)
			(layer "F.Fab")
		)
		(fp_line
			(start 0.67945 -0.3048)
			(end 0.67945 0.3048)
			(stroke
				(width 0.1)
				(type default)
			)
			(layer "F.Fab")
		)
		(fp_line
			(start -0.67945 -0.305054)
			(end -0.12065 -0.305054)
			(stroke
				(width 0.1)
				(type default)
			)
			(layer "F.Fab")
		)
		(fp_line
			(start -0.12065 -0.305054)
			(end -0.12065 -0.2794)
			(stroke
				(width 0.1)
				(type default)
			)
			(layer "F.Fab")
		)
		(pad "1" smd circle
			(at -0.40005 0 270)
			(size 0 0)
			(layers "F.Cu" "F.Mask" "F.Paste")
			(net "P3V3_AUX")
		)
		(pad "2" smd circle
			(at 0.40005 0 270)
			(size 0 0)
			(layers "F.Cu" "F.Mask" "F.Paste")
			(net "FM_P2E_EQA0")
		)
	)
	(footprint ""
		(layer "F.Cu")
		(at 88.8111 -327.768204)
		(property "Reference" "PL26"
			(at -3.844036 6.909054 0)
			(unlocked yes)
			(layer "F.SilkS")
			(effects
				(font
					(size 0.7874 0.5842)
					(thickness 0.1524)
				)
				(justify left)
			)
		)
		(property "Value" ""
			(at 0 0 0)
			(layer "F.Fab")
			(effects
				(font
					(size 1.27 1.27)
				)
			)
		)
		(duplicate_pad_numbers_are_jumpers no)
		(fp_line
			(start -3.750056 -5.500116)
			(end -2.393442 -5.500116)
			(stroke
				(width 0.1524)
				(type default)
			)
			(layer "F.SilkS")
		)
		(fp_line
			(start -3.750056 5.500116)
			(end -3.750056 -5.500116)
			(stroke
				(width 0.1524)
				(type default)
			)
			(layer "F.SilkS")
		)
		(fp_line
			(start -2.393442 5.500116)
			(end -3.750056 5.500116)
			(stroke
				(width 0.1524)
				(type default)
			)
			(layer "F.SilkS")
		)
		(fp_line
			(start 2.393442 5.500116)
			(end 3.750056 5.500116)
			(stroke
				(width 0.1524)
				(type default)
			)
			(layer "F.SilkS")
		)
		(fp_line
			(start 3.750056 -5.500116)
			(end 2.393442 -5.500116)
			(stroke
				(width 0.1524)
				(type default)
			)
			(layer "F.SilkS")
		)
		(fp_line
			(start 3.750056 5.500116)
			(end 3.750056 -5.500116)
			(stroke
				(width 0.1524)
				(type default)
			)
			(layer "F.SilkS")
		)
		(fp_poly
			(pts
				(xy -3.255772 -6.952996) (xy -2.896616 -5.875274) (xy -3.974338 -6.23443)
			)
			(stroke
				(width 0)
				(type default)
			)
			(fill yes)
			(layer "F.SilkS")
		)
		(fp_line
			(start -3.750056 -5.500116)
			(end -3.750056 5.500116)
			(stroke
				(width 0.1)
				(type default)
			)
			(layer "F.Fab")
		)
		(fp_line
			(start -3.750056 5.500116)
			(end 3.750056 5.500116)
			(stroke
				(width 0.1)
				(type default)
			)
			(layer "F.Fab")
		)
		(fp_line
			(start 3.750056 -5.500116)
			(end -3.750056 -5.500116)
			(stroke
				(width 0.1)
				(type default)
			)
			(layer "F.Fab")
		)
		(fp_line
			(start 3.750056 5.500116)
			(end 3.750056 -5.500116)
			(stroke
				(width 0.1)
				(type default)
			)
			(layer "F.Fab")
		)
		(fp_poly
			(pts
				(xy -4.9276 -4.757928) (xy -4.9276 -3.741928) (xy -3.9116 -4.249928)
			)
			(stroke
				(width 0)
				(type default)
			)
			(fill yes)
			(layer "F.Fab")
		)
		(pad "1" smd rect
			(at 0 -4.249928 270)
			(size 2.413 4.5212)
			(layers "F.Cu" "F.Mask" "F.Paste")
			(net "SW_PVCCIN_CPU1_SW6")
		)
		(pad "2" smd rect
			(at 0 -1.175004 270)
			(size 1.3716 4.5212)
			(layers "F.Cu" "F.Mask" "F.Paste")
			(net "IND_P1_CPL6")
		)
		(pad "3" smd rect
			(at 0 1.175004 270)
			(size 1.3716 4.5212)
			(layers "F.Cu" "F.Mask" "F.Paste")
			(net "IND_P1_CPL7")
		)
		(pad "4" smd rect
			(at 0 4.249928 270)
			(size 2.413 4.5212)
			(layers "F.Cu" "F.Mask" "F.Paste")
			(net "PVCCIN_CPU1")
		)
	)
	(footprint ""
		(layer "F.Cu")
		(at 36.956238 -130.76174 180)
		(property "Reference" "R2560"
			(at 0 0 180)
			(layer "F.SilkS")
			(hide yes)
			(effects
				(font
					(size 1.27 1.27)
				)
			)
		)
		(property "Value" ""
			(at 0 0 180)
			(layer "F.Fab")
			(effects
				(font
					(size 1.27 1.27)
				)
			)
		)
		(duplicate_pad_numbers_are_jumpers no)
		(fp_line
			(start 0.7874 0.4064)
			(end -0.7874 0.4064)
			(stroke
				(width 0.1524)
				(type default)
			)
			(layer "F.SilkS")
		)
		(fp_line
			(start 0.7874 -0.4064)
			(end 0.7874 0.4064)
			(stroke
				(width 0.1524)
				(type default)
			)
			(layer "F.SilkS")
		)
		(fp_line
			(start -0.7874 0.4064)
			(end -0.7874 -0.4064)
			(stroke
				(width 0.1524)
				(type default)
			)
			(layer "F.SilkS")
		)
		(fp_line
			(start -0.7874 -0.4064)
			(end 0.7874 -0.4064)
			(stroke
				(width 0.1524)
				(type default)
			)
			(layer "F.SilkS")
		)
		(fp_line
			(start 0.67945 0.3048)
			(end 0.120396 0.3048)
			(stroke
				(width 0.1)
				(type default)
			)
			(layer "F.Fab")
		)
		(fp_line
			(start 0.67945 -0.3048)
			(end 0.67945 0.3048)
			(stroke
				(width 0.1)
				(type default)
			)
			(layer "F.Fab")
		)
		(fp_line
			(start 0.12065 -0.2794)
			(end 0.12065 -0.3048)
			(stroke
				(width 0.1)
				(type default)
			)
			(layer "F.Fab")
		)
		(fp_line
			(start 0.12065 -0.3048)
			(end 0.67945 -0.3048)
			(stroke
				(width 0.1)
				(type default)
			)
			(layer "F.Fab")
		)
		(fp_line
			(start 0.120396 0.3048)
			(end 0.120396 0.2794)
			(stroke
				(width 0.1)
				(type default)
			)
			(layer "F.Fab")
		)
		(fp_line
			(start 0.120396 0.2794)
			(end -0.12065 0.2794)
			(stroke
				(width 0.1)
				(type default)
			)
			(layer "F.Fab")
		)
		(fp_line
			(start -0.12065 0.3048)
			(end -0.67945 0.3048)
			(stroke
				(width 0.1)
				(type default)
			)
			(layer "F.Fab")
		)
		(fp_line
			(start -0.12065 0.2794)
			(end -0.12065 0.3048)
			(stroke
				(width 0.1)
				(type default)
			)
			(layer "F.Fab")
		)
		(fp_line
			(start -0.12065 -0.2794)
			(end 0.12065 -0.2794)
			(stroke
				(width 0.1)
				(type default)
			)
			(layer "F.Fab")
		)
		(fp_line
			(start -0.12065 -0.305054)
			(end -0.12065 -0.2794)
			(stroke
				(width 0.1)
				(type default)
			)
			(layer "F.Fab")
		)
		(fp_line
			(start -0.67945 0.3048)
			(end -0.67945 -0.305054)
			(stroke
				(width 0.1)
				(type default)
			)
			(layer "F.Fab")
		)
		(fp_line
			(start -0.67945 -0.305054)
			(end -0.12065 -0.305054)
			(stroke
				(width 0.1)
				(type default)
			)
			(layer "F.Fab")
		)
		(pad "1" smd circle
			(at -0.40005 0 180)
			(size 0 0)
			(layers "F.Cu" "F.Mask" "F.Paste")
			(net "SVID_DIO0_CPU1_R")
		)
		(pad "2" smd circle
			(at 0.40005 0 180)
			(size 0 0)
			(layers "F.Cu" "F.Mask" "F.Paste")
			(net "SVID_DIO_PVCCINFAON_CPU1_R")
		)
	)
)
